# SCM (Grand Teton) — schematic netlist excerpt (pin names and nets, part order shuffled) for the footprints in the layout excerpt that follows; sources: Cadence DE-HDL packaged netlist, KiCad conversion of 12092022_DA0F0TMDCD0_F0T_Management_Board_D_brd_V3_OCP.brd

PC254  Q_CAP  0.22UF 16V 10% X7R  pkg 0402  page 55 : A = SW_P1V2_AUX_BST ; B = SW_P1V2_AUX_SW
H1  HOLE  EMPTY  pkg TH  page 57 : \1\ = GND
R763  Q_RES  33.2 1% CHIP  pkg 0402LF  page 13 : A = FM_PCH_BMC_THERMTRIP_N ; B = FM_PLT_BMC_THERMTRIP_N_R

(kicad_pcb
	(version 20260206)
	(generator "pcbnew")
	(generator_version "10.0")
	(general
		(thickness 1.6)
		(legacy_teardrops no)
	)
	(paper "A4")
	(title_block
		(title "12092022_DA0F0TMDCD0_F0T_Management_Board_D_brd_V3_OCP.brd")
		(comment 1 "Grand Teton / footprints 196-198 of 1440")
	)
	(layers
		(0 "F.Cu" signal "TOP")
		(4 "In1.Cu" signal "GND")
		(6 "In2.Cu" signal "IN1")
		(8 "In3.Cu" signal "GND1")
		(10 "In4.Cu" signal "IN2")
		(12 "In5.Cu" signal "VCC")
		(14 "In6.Cu" signal "VCC1")
		(16 "In7.Cu" signal "IN3")
		(18 "In8.Cu" signal "GND2")
		(20 "In9.Cu" signal "IN4")
		(22 "In10.Cu" signal "GND3")
		(2 "B.Cu" signal "BOTTOM")
		(9 "F.Adhes" user "F.Adhesive")
		(11 "B.Adhes" user "B.Adhesive")
		(13 "F.Paste" user "Package Geometry/Pastemask Top")
		(15 "B.Paste" user "Package Geometry/Pastemask Bottom")
		(5 "F.SilkS" user "Ref Des/Silkscreen Top")
		(7 "B.SilkS" user "Ref Des/Silkscreen Bottom")
		(1 "F.Mask" user "Board Geometry/Soldermask Top")
		(3 "B.Mask" user "Board Geometry/Soldermask Bottom")
		(17 "Dwgs.User" user "User.Drawings")
		(19 "Cmts.User" user "User.Comments")
		(21 "Eco1.User" user "User.Eco1")
		(23 "Eco2.User" user "User.Eco2")
		(25 "Edge.Cuts" user "Board Geometry/Outline")
		(27 "Margin" user)
		(31 "F.CrtYd" user "Package Geometry/Place Bound Top")
		(29 "B.CrtYd" user "Package Geometry/Place Bound Bottom")
		(35 "F.Fab" user "Ref Des/Assembly Top")
		(33 "B.Fab" user "Ref Des/Assembly Bottom")
	)
	(footprint ""
		(layer "F.Cu")
		(at 82.01152 -70.08876 180)
		(property "Reference" "PC254"
			(at 0 0 180)
			(layer "F.SilkS")
			(hide yes)
			(effects
				(font
					(size 1.27 1.27)
				)
			)
		)
		(property "Value" ""
			(at 0 0 180)
			(layer "F.Fab")
			(effects
				(font
					(size 1.27 1.27)
				)
			)
		)
		(duplicate_pad_numbers_are_jumpers no)
		(fp_line
			(start 0.7874 0.4064)
			(end -0.7874 0.4064)
			(stroke
				(width 0.1524)
				(type default)
			)
			(layer "F.SilkS")
		)
		(fp_line
			(start 0.7874 -0.4064)
			(end 0.7874 0.4064)
			(stroke
				(width 0.1524)
				(type default)
			)
			(layer "F.SilkS")
		)
		(fp_line
			(start -0.7874 0.4064)
			(end -0.7874 -0.4064)
			(stroke
				(width 0.1524)
				(type default)
			)
			(layer "F.SilkS")
		)
		(fp_line
			(start -0.7874 -0.4064)
			(end 0.7874 -0.4064)
			(stroke
				(width 0.1524)
				(type default)
			)
			(layer "F.SilkS")
		)
		(fp_line
			(start 0.67945 0.3048)
			(end 0.120396 0.3048)
			(stroke
				(width 0.1)
				(type default)
			)
			(layer "F.Fab")
		)
		(fp_line
			(start 0.67945 -0.3048)
			(end 0.67945 0.3048)
			(stroke
				(width 0.1)
				(type default)
			)
			(layer "F.Fab")
		)
		(fp_line
			(start 0.12065 -0.2794)
			(end 0.12065 -0.3048)
			(stroke
				(width 0.1)
				(type default)
			)
			(layer "F.Fab")
		)
		(fp_line
			(start 0.12065 -0.3048)
			(end 0.67945 -0.3048)
			(stroke
				(width 0.1)
				(type default)
			)
			(layer "F.Fab")
		)
		(fp_line
			(start 0.120396 0.3048)
			(end 0.120396 0.2794)
			(stroke
				(width 0.1)
				(type default)
			)
			(layer "F.Fab")
		)
		(fp_line
			(start 0.120396 0.2794)
			(end -0.12065 0.2794)
			(stroke
				(width 0.1)
				(type default)
			)
			(layer "F.Fab")
		)
		(fp_line
			(start -0.12065 0.3048)
			(end -0.67945 0.3048)
			(stroke
				(width 0.1)
				(type default)
			)
			(layer "F.Fab")
		)
		(fp_line
			(start -0.12065 0.2794)
			(end -0.12065 0.3048)
			(stroke
				(width 0.1)
				(type default)
			)
			(layer "F.Fab")
		)
		(fp_line
			(start -0.12065 -0.2794)
			(end 0.12065 -0.2794)
			(stroke
				(width 0.1)
				(type default)
			)
			(layer "F.Fab")
		)
		(fp_line
			(start -0.12065 -0.305054)
			(end -0.12065 -0.2794)
			(stroke
				(width 0.1)
				(type default)
			)
			(layer "F.Fab")
		)
		(fp_line
			(start -0.67945 0.3048)
			(end -0.67945 -0.305054)
			(stroke
				(width 0.1)
				(type default)
			)
			(layer "F.Fab")
		)
		(fp_line
			(start -0.67945 -0.305054)
			(end -0.12065 -0.305054)
			(stroke
				(width 0.1)
				(type default)
			)
			(layer "F.Fab")
		)
		(pad "1" smd circle
			(at -0.40005 0 180)
			(size 0 0)
			(layers "F.Cu" "F.Mask" "F.Paste")
			(net "SW_P1V2_AUX_BST")
		)
		(pad "2" smd circle
			(at 0.40005 0 180)
			(size 0 0)
			(layers "F.Cu" "F.Mask" "F.Paste")
			(net "SW_P1V2_AUX_SW")
		)
	)
	(footprint ""
		(layer "F.Cu")
		(at 46.736 -34.6456 90)
		(property "Reference" "R763"
			(at 0 0 90)
			(layer "F.SilkS")
			(hide yes)
			(effects
				(font
					(size 1.27 1.27)
				)
			)
		)
		(property "Value" ""
			(at 0 0 90)
			(layer "F.Fab")
			(effects
				(font
					(size 1.27 1.27)
				)
			)
		)
		(duplicate_pad_numbers_are_jumpers no)
		(fp_line
			(start 0.7874 -0.4064)
			(end 0.7874 0.4064)
			(stroke
				(width 0.1524)
				(type default)
			)
			(layer "F.SilkS")
		)
		(fp_line
			(start -0.7874 -0.4064)
			(end 0.7874 -0.4064)
			(stroke
				(width 0.1524)
				(type default)
			)
			(layer "F.SilkS")
		)
		(fp_line
			(start 0.7874 0.4064)
			(end -0.7874 0.4064)
			(stroke
				(width 0.1524)
				(type default)
			)
			(layer "F.SilkS")
		)
		(fp_line
			(start -0.7874 0.4064)
			(end -0.7874 -0.4064)
			(stroke
				(width 0.1524)
				(type default)
			)
			(layer "F.SilkS")
		)
		(fp_line
			(start -0.12065 -0.305054)
			(end -0.12065 -0.2794)
			(stroke
				(width 0.1)
				(type default)
			)
			(layer "F.Fab")
		)
		(fp_line
			(start -0.67945 -0.305054)
			(end -0.12065 -0.305054)
			(stroke
				(width 0.1)
				(type default)
			)
			(layer "F.Fab")
		)
		(fp_line
			(start 0.67945 -0.3048)
			(end 0.67945 0.3048)
			(stroke
				(width 0.1)
				(type default)
			)
			(layer "F.Fab")
		)
		(fp_line
			(start 0.12065 -0.3048)
			(end 0.67945 -0.3048)
			(stroke
				(width 0.1)
				(type default)
			)
			(layer "F.Fab")
		)
		(fp_line
			(start 0.12065 -0.2794)
			(end 0.12065 -0.3048)
			(stroke
				(width 0.1)
				(type default)
			)
			(layer "F.Fab")
		)
		(fp_line
			(start -0.12065 -0.2794)
			(end 0.12065 -0.2794)
			(stroke
				(width 0.1)
				(type default)
			)
			(layer "F.Fab")
		)
		(fp_line
			(start 0.120396 0.2794)
			(end -0.12065 0.2794)
			(stroke
				(width 0.1)
				(type default)
			)
			(layer "F.Fab")
		)
		(fp_line
			(start -0.12065 0.2794)
			(end -0.12065 0.3048)
			(stroke
				(width 0.1)
				(type default)
			)
			(layer "F.Fab")
		)
		(fp_line
			(start 0.67945 0.3048)
			(end 0.120396 0.3048)
			(stroke
				(width 0.1)
				(type default)
			)
			(layer "F.Fab")
		)
		(fp_line
			(start 0.120396 0.3048)
			(end 0.120396 0.2794)
			(stroke
				(width 0.1)
				(type default)
			)
			(layer "F.Fab")
		)
		(fp_line
			(start -0.12065 0.3048)
			(end -0.67945 0.3048)
			(stroke
				(width 0.1)
				(type default)
			)
			(layer "F.Fab")
		)
		(fp_line
			(start -0.67945 0.3048)
			(end -0.67945 -0.305054)
			(stroke
				(width 0.1)
				(type default)
			)
			(layer "F.Fab")
		)
		(pad "1" smd circle
			(at -0.40005 0 90)
			(size 0 0)
			(layers "F.Cu" "F.Mask" "F.Paste")
			(net "FM_PCH_BMC_THERMTRIP_N")
		)
		(pad "2" smd circle
			(at 0.40005 0 90)
			(size 0 0)
			(layers "F.Cu" "F.Mask" "F.Paste")
			(net "FM_PLT_BMC_THERMTRIP_N_R")
		)
	)
	(footprint ""
		(layer "F.Cu")
		(at 26.750264 -54.189122)
		(property "Reference" "H1"
			(at -1.7272 -4.511548 0)
			(unlocked yes)
			(layer "B.SilkS")
			(effects
				(font
					(size 0.7874 0.5842)
					(thickness 0.1524)
				)
				(justify left mirror)
			)
		)
		(property "Value" ""
			(at 0 0 0)
			(layer "F.Fab")
			(effects
				(font
					(size 1.27 1.27)
				)
			)
		)
		(duplicate_pad_numbers_are_jumpers no)
		(pad "1" thru_hole circle
			(at 0 0)
			(size 4.5212 4.5212)
			(drill 3.81)
			(layers "*.Cu" "*.Mask")
			(remove_unused_layers no)
			(net "GND")
			(clearance -0.1016)
			(padstack
				(mode front_inner_back)
				(layer "Inner"
					(shape circle)
					(size 5.6134 5.6134)
					(clearance -0.6477)
				)
				(layer "B.Cu"
					(shape circle)
					(size 8.001 8.001)
					(clearance -1.8415)
				)
			)
		)
	)
)
